# S9S_MB_2U (Grand Teton) — schematic netlist excerpt (pin names and nets, part order shuffled) for the footprints in the layout excerpt that follows; sources: Cadence DE-HDL packaged netlist, KiCad conversion of 03242023_DA0F0TMBIJ0_F0T_Motherboard_J_brd_V01_OCP.brd

J26  SCONN288_ADR50017P087CC  SCONN288_ADR50017-P087CC IO  pkg DDR288S_1-1VXB  page 107
  VIN_BULK0  = P12V_S3_AUX_CPU1_NVDIMM
  RFU0  = TP_CHE_CPU1_DIMM2_FRU_0
  VIN_MGMT  = P3V3_AUX
  HSCL  = I3C_SPD_DDREFGH_CPU1_LVC1_SCL_1
  HSDA  = I3C_SPD_DDREFGH_CPU1_LVC1_SDA
  VSS0  = GND
  DQ0_A  = M_E_CPU1_SA_DQ<0>
  VSS1  = GND
  DQ1_A  = M_E_CPU1_SA_DQ<1>
  VSS2  = GND
  DQS0_A_T  = M_E_CPU1_SA_DQS_DP<0>
  DQS0_A_C  = M_E_CPU1_SA_DQS_DN<0>
  VSS3  = GND
  DQ4_A  = M_E_CPU1_SA_DQ<4>
  VSS4  = GND
  DQ5_A  = M_E_CPU1_SA_DQ<5>
  VSS5  = GND
  DQ8_A  = M_E_CPU1_SA_DQ<8>
  VSS6  = GND
  DQ9_A  = M_E_CPU1_SA_DQ<9>
  VSS7  = GND
  DQS1_A_T  = M_E_CPU1_SA_DQS_DP<1>
  DQS1_A_C  = M_E_CPU1_SA_DQS_DN<1>
  VSS8  = GND
  DQ12_A  = M_E_CPU1_SA_DQ<12>
  VSS9  = GND
  DQ13_A  = M_E_CPU1_SA_DQ<13>
  VSS10  = GND
  DQ16_A  = M_E_CPU1_SA_DQ<16>
  VSS11  = GND
  DQ17_A  = M_E_CPU1_SA_DQ<17>
  VSS12  = GND
  DQS2_A_T  = M_E_CPU1_SA_DQS_DP<2>
  DQS2_A_C  = M_E_CPU1_SA_DQS_DN<2>
  VSS13  = GND
  DQ20_A  = M_E_CPU1_SA_DQ<20>
  VSS14  = GND
  DQ21_A  = M_E_CPU1_SA_DQ<21>
  VSS15  = GND
  DQ24_A  = M_E_CPU1_SA_DQ<24>
  VSS16  = GND
  DQ25_A  = M_E_CPU1_SA_DQ<25>
  VSS17  = GND
  DQS3_A_T  = M_E_CPU1_SA_DQS_DP<3>
  DQS3_A_C  = M_E_CPU1_SA_DQS_DN<3>
  VSS18  = GND
  DQ28_A  = M_E_CPU1_SA_DQ<28>
  VSS19  = GND
  DQ29_A  = M_E_CPU1_SA_DQ<29>
  VSS20  = GND
  CB0_A  = M_E_CPU1_SA_CB<0>
  VSS21  = GND
  CB1_A  = M_E_CPU1_SA_CB<1>
  VSS22  = GND
  DQS4_A_T  = M_E_CPU1_SA_DQS_DP<4>
  DQS4_A_C  = M_E_CPU1_SA_DQS_DN<4>
  VSS23  = GND
  CB4_A  = M_E_CPU1_SA_CB<4>
  VSS24  = GND
  CB5_A  = M_E_CPU1_SA_CB<5>
  VSS25  = GND
  ALERT_N  = M_E_CPU1_ALERT_N
  VSS26  = GND
  CS0_A_N  = M_E_CPU1_SA_CS_N<2>
  VSS27  = GND
  CA0_A  = M_E_CPU1_SA_CA<0>
  VSS28  = GND
  CA2_A  = M_E_CPU1_SA_CA<2>
  VSS29  = GND
  CA4_A  = M_E_CPU1_SA_CA<4>
  VSS30  = GND
  CA6_A  = M_E_CPU1_SA_CA<6>
  VSS31  = GND
  PAR_A  = M_E_CPU1_SA_PAR
  VSS32  = GND
  CA0_B  = M_E_CPU1_SB_CA<0>
  VSS33  = GND
  CA2_B  = M_E_CPU1_SB_CA<2>
  VSS34  = GND
  CA4_B  = M_E_CPU1_SB_CA<4>
  VSS35  = GND
  CA6_B  = M_E_CPU1_SB_CA<6>
  VSS36  = GND
  CS0_B_N  = M_E_CPU1_SB_CS_N<2>
  VSS37  = GND
  \lbd||rsp_a_n\  = M_E_CPU1_SA_RSP<1>
  \lbs||rsp_b_n\  = M_E_CPU1_SB_RSP<1>
  VSS38  = GND
  CB4_B  = M_E_CPU1_SB_CB<4>
  VSS39  = GND
  CB5_B  = M_E_CPU1_SB_CB<5>
  VSS40  = GND
  \dqs9_b_t||tdqs9_b_t||dbi4_b_n\  = M_E_CPU1_SB_DQS_DP<9>
  \dqs9_b_c||tdqs9_b_c\  = M_E_CPU1_SB_DQS_DN<9>
  VSS41  = GND
  CB0_B  = M_E_CPU1_SB_CB<0>
  VSS42  = GND
  CB1_B  = M_E_CPU1_SB_CB<1>
  VSS43  = GND
  DQ0_B  = M_E_CPU1_SB_DQ<0>
  VSS44  = GND
  DQ1_B  = M_E_CPU1_SB_DQ<1>
  VSS45  = GND
  DQS0_B_T  = M_E_CPU1_SB_DQS_DP<0>
  DQS0_B_C  = M_E_CPU1_SB_DQS_DN<0>
  VSS46  = GND
  DQ4_B  = M_E_CPU1_SB_DQ<4>
  VSS47  = GND
  DQ5_B  = M_E_CPU1_SB_DQ<5>
  VSS48  = GND
  DQ8_B  = M_E_CPU1_SB_DQ<8>
  VSS49  = GND
  DQ9_B  = M_E_CPU1_SB_DQ<9>
  VSS50  = GND
  DQS1_B_T  = M_E_CPU1_SB_DQS_DP<1>
  DQS1_B_C  = M_E_CPU1_SB_DQS_DN<1>
  VSS51  = GND
  DQ12_B  = M_E_CPU1_SB_DQ<12>
  VSS52  = GND
  DQ13_B  = M_E_CPU1_SB_DQ<13>
  VSS53  = GND
  DQ16_B  = M_E_CPU1_SB_DQ<16>
  VSS54  = GND
  DQ17_B  = M_E_CPU1_SB_DQ<17>
  VSS55  = GND
  DQS2_B_T  = M_E_CPU1_SB_DQS_DP<2>
  DQS2_B_C  = M_E_CPU1_SB_DQS_DN<2>
  VSS56  = GND
  DQ20_B  = M_E_CPU1_SB_DQ<20>
  VSS57  = GND
  DQ21_B  = M_E_CPU1_SB_DQ<21>
  VSS58  = GND
  DQ24_B  = M_E_CPU1_SB_DQ<24>
  VSS59  = GND
  DQ25_B  = M_E_CPU1_SB_DQ<25>
  VSS60  = GND
  DQS3_B_T  = M_E_CPU1_SB_DQS_DP<3>
  DQS3_B_C  = M_E_CPU1_SB_DQS_DN<3>
  VSS61  = GND
  DQ28_B  = M_E_CPU1_SB_DQ<28>
  VSS62  = GND
  DQ29_B  = M_E_CPU1_SB_DQ<29>
  VSS63  = GND
  RFU1  = TP_CHE_CPU1_DIMM2_FRU_1
  VIN_BULK1  = P12V_S3_AUX_CPU1_NVDIMM
  VIN_BULK2  = P12V_S3_AUX_CPU1_NVDIMM
  \pwr_good||fail_n\  = PWRGD_CHE_CPU1_DIMM2
  HSA  = PD_CHE_CPU1_DIMM2_SAA
  RFU2  = TP_CHE_CPU1_DIMM2_FRU_2
  RFU3  = TP_CHE_CPU1_DIMM2_FRU_3
  VSS64  = GND
  DQ2_A  = M_E_CPU1_SA_DQ<2>
  VSS65  = GND
  DQ3_A  = M_E_CPU1_SA_DQ<3>
  VSS66  = GND
  \dqs5_a_c||tdqs5_a_c||dqs5_a_t||tdqs5_a_t\  = M_E_CPU1_SA_DQS_DN<5>
  \dqs5_a_t||tdqs5_a_t\  = M_E_CPU1_SA_DQS_DP<5>
  VSS67  = GND
  DQ6_A  = M_E_CPU1_SA_DQ<6>
  VSS68  = GND
  DQ7_A  = M_E_CPU1_SA_DQ<7>
  VSS69  = GND
  DQ10_A  = M_E_CPU1_SA_DQ<10>
  VSS70  = GND
  DQ11_A  = M_E_CPU1_SA_DQ<11>
  VSS71  = GND
  \dqs6_a_c||tdqs6_a_c||dqs6_a_t||tdqs6_a_t\  = M_E_CPU1_SA_DQS_DN<6>
  \dqs6_a_t||tdqs6_a_t\  = M_E_CPU1_SA_DQS_DP<6>
  VSS72  = GND
  DQ14_A  = M_E_CPU1_SA_DQ<14>
  VSS73  = GND
  DQ15_A  = M_E_CPU1_SA_DQ<15>
  VSS74  = GND
  DQ18_A  = M_E_CPU1_SA_DQ<18>
  VSS75  = GND
  DQ19_A  = M_E_CPU1_SA_DQ<19>
  VSS76  = GND
  \dqs7_a_c||tdqs7_a_c\  = M_E_CPU1_SA_DQS_DN<7>
  \dqs7_a_t||tdqs7_a_t\  = M_E_CPU1_SA_DQS_DP<7>
  VSS77  = GND
  DQ22_A  = M_E_CPU1_SA_DQ<22>
  VSS78  = GND
  DQ23_A  = M_E_CPU1_SA_DQ<23>
  VSS79  = GND
  DQ26_A  = M_E_CPU1_SA_DQ<26>
  VSS80  = GND
  DQ27_A  = M_E_CPU1_SA_DQ<27>
  VSS81  = GND
  \dqs8_a_c||tdqs8_a_c\  = M_E_CPU1_SA_DQS_DN<8>
  \dqs8_a_t||tdqs8_a_t\  = M_E_CPU1_SA_DQS_DP<8>
  VSS82  = GND
  DQ30_A  = M_E_CPU1_SA_DQ<30>
  VSS83  = GND
  DQ31_A  = M_E_CPU1_SA_DQ<31>
  VSS84  = GND
  CB2_A  = M_E_CPU1_SA_CB<2>
  VSS85  = GND
  CB3_A  = M_E_CPU1_SA_CB<3>
  VSS86  = GND
  \dqs9_a_c||tdqs9_a_c\  = M_E_CPU1_SA_DQS_DN<9>
  \dqs9_a_t||tdqs9_a_t\  = M_E_CPU1_SA_DQS_DP<9>
  VSS87  = GND
  CB6_A  = M_E_CPU1_SA_CB<6>
  VSS88  = GND
  CB7_A  = M_E_CPU1_SA_CB<7>
  VSS89  = GND
  RESET_N  = RST_M_EF_CPU1_FPGA_N
  VSS90  = GND
  CS1_A_N  = M_E_CPU1_SA_CS_N<3>
  VSS91  = GND
  CA1_A  = M_E_CPU1_SA_CA<1>
  VSS92  = GND
  CA3_A  = M_E_CPU1_SA_CA<3>
  VSS93  = GND
  CA5_A  = M_E_CPU1_SA_CA<5>
  VSS94  = GND
  CK_T  = M_E_CPU1_CLK_DP<1>
  CK_C  = M_E_CPU1_CLK_DN<1>
  VSS95  = GND
  RFU4  = TP_CHE_CPU1_DIMM2_FRU_4
  CA1_B  = M_E_CPU1_SB_CA<1>
  VSS96  = GND
  CA3_B  = M_E_CPU1_SB_CA<3>
  VSS97  = GND
  CA5_B  = M_E_CPU1_SB_CA<5>
  VSS98  = GND
  PAR_B  = M_E_CPU1_SB_PAR
  VSS99  = GND
  CS1_B_N  = M_E_CPU1_SB_CS_N<3>
  VSS100  = GND
  RFU5  = TP_CHE_CPU1_DIMM2_FRU_5
  RFU6  = TP_CHE_CPU1_DIMM2_FRU_6
  VSS101  = GND
  CB6_B  = M_E_CPU1_SB_CB<6>
  VSS102  = GND
  CB7_B  = M_E_CPU1_SB_CB<7>
  VSS103  = GND
  DQS4_B_C  = M_E_CPU1_SB_DQS_DN<4>
  DQS4_B_T  = M_E_CPU1_SB_DQS_DP<4>
  VSS104  = GND
  CB2_B  = M_E_CPU1_SB_CB<2>
  VSS105  = GND
  CB3_B  = M_E_CPU1_SB_CB<3>
  VSS106  = GND
  DQ2_B  = M_E_CPU1_SB_DQ<2>
  VSS107  = GND
  DQ3_B  = M_E_CPU1_SB_DQ<3>
  VSS108  = GND
  \dqs5_b_c||tdqs5_b_c\  = M_E_CPU1_SB_DQS_DN<5>
  \dqs5_b_t||tdqs5_b_t\  = M_E_CPU1_SB_DQS_DP<5>
  VSS109  = GND
  DQ6_B  = M_E_CPU1_SB_DQ<6>
  VSS110  = GND
  DQ7_B  = M_E_CPU1_SB_DQ<7>
  VSS111  = GND
  DQ10_B  = M_E_CPU1_SB_DQ<10>
  VSS112  = GND
  DQ11_B  = M_E_CPU1_SB_DQ<11>
  VSS113  = GND
  \dqs6_b_c||tdqs6_b_c\  = M_E_CPU1_SB_DQS_DN<6>
  \dqs6_b_t||tdqs6_b_t\  = M_E_CPU1_SB_DQS_DP<6>
  VSS114  = GND
  DQ14_B  = M_E_CPU1_SB_DQ<14>
  VSS115  = GND
  DQ15_B  = M_E_CPU1_SB_DQ<15>
  VSS116  = GND
  DQ18_B  = M_E_CPU1_SB_DQ<18>
  VSS117  = GND
  DQ19_B  = M_E_CPU1_SB_DQ<19>
  VSS118  = GND
  \dqs7_b_c||tdqs7_b_c\  = M_E_CPU1_SB_DQS_DN<7>
  \dqs7_b_t||tdqs7_b_t\  = M_E_CPU1_SB_DQS_DP<7>
  VSS119  = GND
  DQ22_B  = M_E_CPU1_SB_DQ<22>
  VSS120  = GND
  DQ23_B  = M_E_CPU1_SB_DQ<23>
  VSS121  = GND
  DQ26_B  = M_E_CPU1_SB_DQ<26>
  VSS122  = GND
  DQ27_B  = M_E_CPU1_SB_DQ<27>
  VSS123  = GND
  \dqs8_b_c||tdqs8_b_c\  = M_E_CPU1_SB_DQS_DN<8>
  \dqs8_b_t||tdqs8_b_t\  = M_E_CPU1_SB_DQS_DP<8>
  VSS124  = GND
  DQ30_B  = M_E_CPU1_SB_DQ<30>
  VSS125  = GND
  DQ31_B  = M_E_CPU1_SB_DQ<31>
  VSS126  = GND
  G1  = GND
  G2  = GND
  G3  = GND

(kicad_pcb
	(version 20260206)
	(generator "pcbnew")
	(generator_version "10.0")
	(general
		(thickness 1.6)
		(legacy_teardrops no)
	)
	(paper "A4")
	(title_block
		(title "03242023_DA0F0TMBIJ0_F0T_Motherboard_J_brd_V01_OCP.brd")
		(comment 1 "Grand Teton / footprint 1065 of 6105 (J26), pads 138-182 of 291")
	)
	(layers
		(0 "F.Cu" signal "TOP")
		(4 "In1.Cu" signal "GND")
		(6 "In2.Cu" signal "IN1")
		(8 "In3.Cu" signal "GND1")
		(10 "In4.Cu" signal "IN2")
		(12 "In5.Cu" signal "GND2")
		(14 "In6.Cu" signal "IN3")
		(16 "In7.Cu" signal "GND3")
		(18 "In8.Cu" signal "VCC")
		(20 "In9.Cu" signal "VCC1")
		(22 "In10.Cu" signal "GND4")
		(24 "In11.Cu" signal "IN4")
		(26 "In12.Cu" signal "GND5")
		(28 "In13.Cu" signal "IN5")
		(30 "In14.Cu" signal "GND6")
		(32 "In15.Cu" signal "IN6")
		(34 "In16.Cu" signal "GND7")
		(2 "B.Cu" signal "BOTTOM")
		(9 "F.Adhes" user "F.Adhesive")
		(11 "B.Adhes" user "B.Adhesive")
		(13 "F.Paste" user "Package Geometry/Pastemask Top")
		(15 "B.Paste" user "Package Geometry/Pastemask Bottom")
		(5 "F.SilkS" user "Ref Des/Silkscreen Top")
		(7 "B.SilkS" user "Ref Des/Silkscreen Bottom")
		(1 "F.Mask" user "Board Geometry/Soldermask Top")
		(3 "B.Mask" user "Board Geometry/Soldermask Bottom")
		(17 "Dwgs.User" user "User.Drawings")
		(19 "Cmts.User" user "User.Comments")
		(21 "Eco1.User" user "User.Eco1")
		(23 "Eco2.User" user "User.Eco2")
		(25 "Edge.Cuts" user "Board Geometry/Outline")
		(27 "Margin" user)
		(31 "F.CrtYd" user "Package Geometry/Place Bound Top")
		(29 "B.CrtYd" user "Package Geometry/Place Bound Bottom")
		(35 "F.Fab" user "Ref Des/Assembly Top")
		(33 "B.Fab" user "Ref Des/Assembly Bottom")
	)
	(footprint ""
		(layer "F.Cu")
		(at 160.86328 -258.091686)
		(property "Reference" "J26"
			(at -3.683 -81.702148 0)
			(unlocked yes)
			(layer "F.SilkS")
			(effects
				(font
					(size 0.7874 0.5842)
					(thickness 0.1524)
				)
				(justify left)
			)
		)
		(property "Value" ""
			(at 0 0 0)
			(layer "F.Fab")
			(effects
				(font
					(size 1.27 1.27)
				)
			)
		)
		(duplicate_pad_numbers_are_jumpers no)
		(pad "138" smd rect
			(at -2.050034 58.224928 270)
			(size 0.519938 1.4986)
			(layers "F.Cu" "F.Mask" "F.Paste")
			(net "M_E_CPU1_SB_DQS_DN<3>")
		)
		(pad "139" smd rect
			(at -2.050034 59.075066 270)
			(size 0.519938 1.4986)
			(layers "F.Cu" "F.Mask" "F.Paste")
			(net "GND")
		)
		(pad "140" smd rect
			(at -2.050034 59.92495 270)
			(size 0.519938 1.4986)
			(layers "F.Cu" "F.Mask" "F.Paste")
			(net "M_E_CPU1_SB_DQ<28>")
		)
		(pad "141" smd rect
			(at -2.050034 60.775088 270)
			(size 0.519938 1.4986)
			(layers "F.Cu" "F.Mask" "F.Paste")
			(net "GND")
		)
		(pad "142" smd rect
			(at -2.050034 61.624972 270)
			(size 0.519938 1.4986)
			(layers "F.Cu" "F.Mask" "F.Paste")
			(net "M_E_CPU1_SB_DQ<29>")
		)
		(pad "143" smd rect
			(at -2.050034 62.47511 270)
			(size 0.519938 1.4986)
			(layers "F.Cu" "F.Mask" "F.Paste")
			(net "GND")
		)
		(pad "144" smd rect
			(at -2.050034 63.324994 270)
			(size 0.519938 1.4986)
			(layers "F.Cu" "F.Mask" "F.Paste")
			(net "TP_CHE_CPU1_DIMM2_FRU_1")
		)
		(pad "145" smd rect
			(at 2.050034 -63.324994 270)
			(size 0.519938 1.4986)
			(layers "F.Cu" "F.Mask" "F.Paste")
			(net "P12V_S3_AUX_CPU1_NVDIMM")
		)
		(pad "146" smd rect
			(at 2.050034 -62.47511 270)
			(size 0.519938 1.4986)
			(layers "F.Cu" "F.Mask" "F.Paste")
			(net "P12V_S3_AUX_CPU1_NVDIMM")
		)
		(pad "147" smd rect
			(at 2.050034 -61.624972 270)
			(size 0.519938 1.4986)
			(layers "F.Cu" "F.Mask" "F.Paste")
			(net "PWRGD_CHE_CPU1_DIMM2")
		)
		(pad "148" smd rect
			(at 2.050034 -60.775088 270)
			(size 0.519938 1.4986)
			(layers "F.Cu" "F.Mask" "F.Paste")
			(net "PD_CHE_CPU1_DIMM2_SAA")
		)
		(pad "149" smd rect
			(at 2.050034 -59.92495 270)
			(size 0.519938 1.4986)
			(layers "F.Cu" "F.Mask" "F.Paste")
			(net "TP_CHE_CPU1_DIMM2_FRU_2")
		)
		(pad "150" smd rect
			(at 2.050034 -59.075066 270)
			(size 0.519938 1.4986)
			(layers "F.Cu" "F.Mask" "F.Paste")
			(net "TP_CHE_CPU1_DIMM2_FRU_3")
		)
		(pad "151" smd rect
			(at 2.050034 -58.224928 270)
			(size 0.519938 1.4986)
			(layers "F.Cu" "F.Mask" "F.Paste")
			(net "GND")
		)
		(pad "152" smd rect
			(at 2.050034 -57.375044 270)
			(size 0.519938 1.4986)
			(layers "F.Cu" "F.Mask" "F.Paste")
			(net "M_E_CPU1_SA_DQ<2>")
		)
		(pad "153" smd rect
			(at 2.050034 -56.524906 270)
			(size 0.519938 1.4986)
			(layers "F.Cu" "F.Mask" "F.Paste")
			(net "GND")
		)
		(pad "154" smd rect
			(at 2.050034 -55.675022 270)
			(size 0.519938 1.4986)
			(layers "F.Cu" "F.Mask" "F.Paste")
			(net "M_E_CPU1_SA_DQ<3>")
		)
		(pad "155" smd rect
			(at 2.050034 -54.824884 270)
			(size 0.519938 1.4986)
			(layers "F.Cu" "F.Mask" "F.Paste")
			(net "GND")
		)
		(pad "156" smd rect
			(at 2.050034 -53.975 270)
			(size 0.519938 1.4986)
			(layers "F.Cu" "F.Mask" "F.Paste")
			(net "M_E_CPU1_SA_DQS_DN<5>")
		)
		(pad "157" smd rect
			(at 2.050034 -53.125116 270)
			(size 0.519938 1.4986)
			(layers "F.Cu" "F.Mask" "F.Paste")
			(net "M_E_CPU1_SA_DQS_DP<5>")
		)
		(pad "158" smd rect
			(at 2.050034 -52.274978 270)
			(size 0.519938 1.4986)
			(layers "F.Cu" "F.Mask" "F.Paste")
			(net "GND")
		)
		(pad "159" smd rect
			(at 2.050034 -51.425094 270)
			(size 0.519938 1.4986)
			(layers "F.Cu" "F.Mask" "F.Paste")
			(net "M_E_CPU1_SA_DQ<6>")
		)
		(pad "160" smd rect
			(at 2.050034 -50.574956 270)
			(size 0.519938 1.4986)
			(layers "F.Cu" "F.Mask" "F.Paste")
			(net "GND")
		)
		(pad "161" smd rect
			(at 2.050034 -49.725072 270)
			(size 0.519938 1.4986)
			(layers "F.Cu" "F.Mask" "F.Paste")
			(net "M_E_CPU1_SA_DQ<7>")
		)
		(pad "162" smd rect
			(at 2.050034 -48.874934 270)
			(size 0.519938 1.4986)
			(layers "F.Cu" "F.Mask" "F.Paste")
			(net "GND")
		)
		(pad "163" smd rect
			(at 2.050034 -48.02505 270)
			(size 0.519938 1.4986)
			(layers "F.Cu" "F.Mask" "F.Paste")
			(net "M_E_CPU1_SA_DQ<10>")
		)
		(pad "164" smd rect
			(at 2.050034 -47.174912 270)
			(size 0.519938 1.4986)
			(layers "F.Cu" "F.Mask" "F.Paste")
			(net "GND")
		)
		(pad "165" smd rect
			(at 2.050034 -46.325028 270)
			(size 0.519938 1.4986)
			(layers "F.Cu" "F.Mask" "F.Paste")
			(net "M_E_CPU1_SA_DQ<11>")
		)
		(pad "166" smd rect
			(at 2.050034 -45.47489 270)
			(size 0.519938 1.4986)
			(layers "F.Cu" "F.Mask" "F.Paste")
			(net "GND")
		)
		(pad "167" smd rect
			(at 2.050034 -44.625006 270)
			(size 0.519938 1.4986)
			(layers "F.Cu" "F.Mask" "F.Paste")
			(net "M_E_CPU1_SA_DQS_DN<6>")
		)
		(pad "168" smd rect
			(at 2.050034 -43.775122 270)
			(size 0.519938 1.4986)
			(layers "F.Cu" "F.Mask" "F.Paste")
			(net "M_E_CPU1_SA_DQS_DP<6>")
		)
		(pad "169" smd rect
			(at 2.050034 -42.924984 270)
			(size 0.519938 1.4986)
			(layers "F.Cu" "F.Mask" "F.Paste")
			(net "GND")
		)
		(pad "170" smd rect
			(at 2.050034 -42.0751 270)
			(size 0.519938 1.4986)
			(layers "F.Cu" "F.Mask" "F.Paste")
			(net "M_E_CPU1_SA_DQ<14>")
		)
		(pad "171" smd rect
			(at 2.050034 -41.224962 270)
			(size 0.519938 1.4986)
			(layers "F.Cu" "F.Mask" "F.Paste")
			(net "GND")
		)
		(pad "172" smd rect
			(at 2.050034 -40.375078 270)
			(size 0.519938 1.4986)
			(layers "F.Cu" "F.Mask" "F.Paste")
			(net "M_E_CPU1_SA_DQ<15>")
		)
		(pad "173" smd rect
			(at 2.050034 -39.52494 270)
			(size 0.519938 1.4986)
			(layers "F.Cu" "F.Mask" "F.Paste")
			(net "GND")
		)
		(pad "174" smd rect
			(at 2.050034 -38.675056 270)
			(size 0.519938 1.4986)
			(layers "F.Cu" "F.Mask" "F.Paste")
			(net "M_E_CPU1_SA_DQ<18>")
		)
		(pad "175" smd rect
			(at 2.050034 -37.824918 270)
			(size 0.519938 1.4986)
			(layers "F.Cu" "F.Mask" "F.Paste")
			(net "GND")
		)
		(pad "176" smd rect
			(at 2.050034 -36.975034 270)
			(size 0.519938 1.4986)
			(layers "F.Cu" "F.Mask" "F.Paste")
			(net "M_E_CPU1_SA_DQ<19>")
		)
		(pad "177" smd rect
			(at 2.050034 -36.124896 270)
			(size 0.519938 1.4986)
			(layers "F.Cu" "F.Mask" "F.Paste")
			(net "GND")
		)
		(pad "178" smd rect
			(at 2.050034 -35.275012 270)
			(size 0.519938 1.4986)
			(layers "F.Cu" "F.Mask" "F.Paste")
			(net "M_E_CPU1_SA_DQS_DN<7>")
		)
		(pad "179" smd rect
			(at 2.050034 -34.425128 270)
			(size 0.519938 1.4986)
			(layers "F.Cu" "F.Mask" "F.Paste")
			(net "M_E_CPU1_SA_DQS_DP<7>")
		)
		(pad "180" smd rect
			(at 2.050034 -33.57499 270)
			(size 0.519938 1.4986)
			(layers "F.Cu" "F.Mask" "F.Paste")
			(net "GND")
		)
		(pad "181" smd rect
			(at 2.050034 -32.725106 270)
			(size 0.519938 1.4986)
			(layers "F.Cu" "F.Mask" "F.Paste")
			(net "M_E_CPU1_SA_DQ<22>")
		)
		(pad "182" smd rect
			(at 2.050034 -31.874968 270)
			(size 0.519938 1.4986)
			(layers "F.Cu" "F.Mask" "F.Paste")
			(net "GND")
		)
	)
)
